# S9S_MB_2U (Grand Teton) — schematic netlist excerpt (pin names and nets, part order shuffled) for the footprints in the layout excerpt that follows; sources: Cadence DE-HDL packaged netlist, KiCad conversion of 03242023_DA0F0TMBIJ0_F0T_Motherboard_J_brd_V01_OCP.brd

R519  Q_RES  1 1% CHIP  pkg 0603LF  page 210 : A = P3V3_AUX_CLK_GEN_VDD_CK440 ; B = P3V3_AUX_CLK_GEN_VDDA100M_CK440
C987  Q_CAP  10UF 6.3V 20% X6S  pkg C0402  page 74 : A = PVCCIN_CPU0 ; B = GND

(kicad_pcb
	(version 20260206)
	(generator "pcbnew")
	(generator_version "10.0")
	(general
		(thickness 1.6)
		(legacy_teardrops no)
	)
	(paper "A4")
	(title_block
		(title "03242023_DA0F0TMBIJ0_F0T_Motherboard_J_brd_V01_OCP.brd")
		(comment 1 "Grand Teton / footprints 3481-3482 of 6105")
	)
	(layers
		(0 "F.Cu" signal "TOP")
		(4 "In1.Cu" signal "GND")
		(6 "In2.Cu" signal "IN1")
		(8 "In3.Cu" signal "GND1")
		(10 "In4.Cu" signal "IN2")
		(12 "In5.Cu" signal "GND2")
		(14 "In6.Cu" signal "IN3")
		(16 "In7.Cu" signal "GND3")
		(18 "In8.Cu" signal "VCC")
		(20 "In9.Cu" signal "VCC1")
		(22 "In10.Cu" signal "GND4")
		(24 "In11.Cu" signal "IN4")
		(26 "In12.Cu" signal "GND5")
		(28 "In13.Cu" signal "IN5")
		(30 "In14.Cu" signal "GND6")
		(32 "In15.Cu" signal "IN6")
		(34 "In16.Cu" signal "GND7")
		(2 "B.Cu" signal "BOTTOM")
		(9 "F.Adhes" user "F.Adhesive")
		(11 "B.Adhes" user "B.Adhesive")
		(13 "F.Paste" user "Package Geometry/Pastemask Top")
		(15 "B.Paste" user "Package Geometry/Pastemask Bottom")
		(5 "F.SilkS" user "Ref Des/Silkscreen Top")
		(7 "B.SilkS" user "Ref Des/Silkscreen Bottom")
		(1 "F.Mask" user "Board Geometry/Soldermask Top")
		(3 "B.Mask" user "Board Geometry/Soldermask Bottom")
		(17 "Dwgs.User" user "User.Drawings")
		(19 "Cmts.User" user "User.Comments")
		(21 "Eco1.User" user "User.Eco1")
		(23 "Eco2.User" user "User.Eco2")
		(25 "Edge.Cuts" user "Board Geometry/Outline")
		(27 "Margin" user)
		(31 "F.CrtYd" user "Package Geometry/Place Bound Top")
		(29 "B.CrtYd" user "Package Geometry/Place Bound Bottom")
		(35 "F.Fab" user "Ref Des/Assembly Top")
		(33 "B.Fab" user "Ref Des/Assembly Bottom")
	)
	(footprint ""
		(layer "F.Cu")
		(at 354.270818 -245.634002 -90)
		(property "Reference" "C987"
			(at 0 0 270)
			(layer "F.SilkS")
			(hide yes)
			(effects
				(font
					(size 1.27 1.27)
				)
			)
		)
		(property "Value" ""
			(at 0 0 270)
			(layer "F.Fab")
			(effects
				(font
					(size 1.27 1.27)
				)
			)
		)
		(duplicate_pad_numbers_are_jumpers no)
		(fp_line
			(start -0.7874 0.4064)
			(end -0.7874 -0.4064)
			(stroke
				(width 0.1524)
				(type default)
			)
			(layer "F.SilkS")
		)
		(fp_line
			(start 0.7874 0.4064)
			(end -0.7874 0.4064)
			(stroke
				(width 0.1524)
				(type default)
			)
			(layer "F.SilkS")
		)
		(fp_line
			(start -0.7874 -0.4064)
			(end 0.7874 -0.4064)
			(stroke
				(width 0.1524)
				(type default)
			)
			(layer "F.SilkS")
		)
		(fp_line
			(start 0.7874 -0.4064)
			(end 0.7874 0.4064)
			(stroke
				(width 0.1524)
				(type default)
			)
			(layer "F.SilkS")
		)
		(fp_line
			(start -0.67945 0.3048)
			(end -0.67945 -0.305054)
			(stroke
				(width 0.1)
				(type default)
			)
			(layer "F.Fab")
		)
		(fp_line
			(start -0.12065 0.3048)
			(end -0.67945 0.3048)
			(stroke
				(width 0.1)
				(type default)
			)
			(layer "F.Fab")
		)
		(fp_line
			(start 0.120396 0.3048)
			(end 0.120396 0.2794)
			(stroke
				(width 0.1)
				(type default)
			)
			(layer "F.Fab")
		)
		(fp_line
			(start 0.67945 0.3048)
			(end 0.120396 0.3048)
			(stroke
				(width 0.1)
				(type default)
			)
			(layer "F.Fab")
		)
		(fp_line
			(start -0.12065 0.2794)
			(end -0.12065 0.3048)
			(stroke
				(width 0.1)
				(type default)
			)
			(layer "F.Fab")
		)
		(fp_line
			(start 0.120396 0.2794)
			(end -0.12065 0.2794)
			(stroke
				(width 0.1)
				(type default)
			)
			(layer "F.Fab")
		)
		(fp_line
			(start -0.12065 -0.2794)
			(end 0.12065 -0.2794)
			(stroke
				(width 0.1)
				(type default)
			)
			(layer "F.Fab")
		)
		(fp_line
			(start 0.12065 -0.2794)
			(end 0.12065 -0.3048)
			(stroke
				(width 0.1)
				(type default)
			)
			(layer "F.Fab")
		)
		(fp_line
			(start 0.12065 -0.3048)
			(end 0.67945 -0.3048)
			(stroke
				(width 0.1)
				(type default)
			)
			(layer "F.Fab")
		)
		(fp_line
			(start 0.67945 -0.3048)
			(end 0.67945 0.3048)
			(stroke
				(width 0.1)
				(type default)
			)
			(layer "F.Fab")
		)
		(fp_line
			(start -0.67945 -0.305054)
			(end -0.12065 -0.305054)
			(stroke
				(width 0.1)
				(type default)
			)
			(layer "F.Fab")
		)
		(fp_line
			(start -0.12065 -0.305054)
			(end -0.12065 -0.2794)
			(stroke
				(width 0.1)
				(type default)
			)
			(layer "F.Fab")
		)
		(pad "1" smd circle
			(at -0.40005 0 270)
			(size 0 0)
			(layers "F.Cu" "F.Mask" "F.Paste")
			(net "PVCCIN_CPU0")
		)
		(pad "2" smd circle
			(at 0.40005 0 270)
			(size 0 0)
			(layers "F.Cu" "F.Mask" "F.Paste")
			(net "GND")
		)
	)
	(footprint ""
		(layer "F.Cu")
		(at 263.517126 -93.457776)
		(property "Reference" "R519"
			(at 0 0 0)
			(layer "F.SilkS")
			(hide yes)
			(effects
				(font
					(size 1.27 1.27)
				)
			)
		)
		(property "Value" ""
			(at 0 0 0)
			(layer "F.Fab")
			(effects
				(font
					(size 1.27 1.27)
				)
			)
		)
		(duplicate_pad_numbers_are_jumpers no)
		(fp_line
			(start -1.2954 -0.5842)
			(end 1.2954 -0.5842)
			(stroke
				(width 0.1524)
				(type default)
			)
			(layer "F.SilkS")
		)
		(fp_line
			(start -1.2954 0.5842)
			(end -1.2954 -0.5842)
			(stroke
				(width 0.1524)
				(type default)
			)
			(layer "F.SilkS")
		)
		(fp_line
			(start 1.2954 -0.5842)
			(end 1.2954 0.5842)
			(stroke
				(width 0.1524)
				(type default)
			)
			(layer "F.SilkS")
		)
		(fp_line
			(start 1.2954 0.5842)
			(end -1.2954 0.5842)
			(stroke
				(width 0.1524)
				(type default)
			)
			(layer "F.SilkS")
		)
		(fp_line
			(start -1.1938 -0.406654)
			(end -0.8636 -0.406654)
			(stroke
				(width 0.1)
				(type default)
			)
			(layer "F.Fab")
		)
		(fp_line
			(start -1.1938 0.4064)
			(end -1.1938 -0.406654)
			(stroke
				(width 0.1)
				(type default)
			)
			(layer "F.Fab")
		)
		(fp_line
			(start -0.8636 -0.4572)
			(end 0.8636 -0.4572)
			(stroke
				(width 0.1)
				(type default)
			)
			(layer "F.Fab")
		)
		(fp_line
			(start -0.8636 -0.406654)
			(end -0.8636 -0.4572)
			(stroke
				(width 0.1)
				(type default)
			)
			(layer "F.Fab")
		)
		(fp_line
			(start -0.8636 0.4064)
			(end -1.1938 0.4064)
			(stroke
				(width 0.1)
				(type default)
			)
			(layer "F.Fab")
		)
		(fp_line
			(start -0.8636 0.4318)
			(end -0.8636 0.4064)
			(stroke
				(width 0.1)
				(type default)
			)
			(layer "F.Fab")
		)
		(fp_line
			(start -0.8636 0.4572)
			(end -0.8636 0.4318)
			(stroke
				(width 0.1)
				(type default)
			)
			(layer "F.Fab")
		)
		(fp_line
			(start 0.8636 -0.4572)
			(end 0.8636 -0.406654)
			(stroke
				(width 0.1)
				(type default)
			)
			(layer "F.Fab")
		)
		(fp_line
			(start 0.8636 -0.406654)
			(end 1.1938 -0.406654)
			(stroke
				(width 0.1)
				(type default)
			)
			(layer "F.Fab")
		)
		(fp_line
			(start 0.8636 0.4064)
			(end 0.8636 0.4572)
			(stroke
				(width 0.1)
				(type default)
			)
			(layer "F.Fab")
		)
		(fp_line
			(start 0.8636 0.4572)
			(end -0.8636 0.4572)
			(stroke
				(width 0.1)
				(type default)
			)
			(layer "F.Fab")
		)
		(fp_line
			(start 1.1938 -0.406654)
			(end 1.1938 0.4064)
			(stroke
				(width 0.1)
				(type default)
			)
			(layer "F.Fab")
		)
		(fp_line
			(start 1.1938 0.4064)
			(end 0.8636 0.4064)
			(stroke
				(width 0.1)
				(type default)
			)
			(layer "F.Fab")
		)
		(pad "1" smd rect
			(at -0.7366 0 270)
			(size 0.7112 0.8128)
			(layers "F.Cu" "F.Mask" "F.Paste")
			(net "P3V3_AUX_CLK_GEN_VDD_CK440")
		)
		(pad "2" smd rect
			(at 0.7366 0 270)
			(size 0.7112 0.8128)
			(layers "F.Cu" "F.Mask" "F.Paste")
			(net "P3V3_AUX_CLK_GEN_VDDA100M_CK440")
		)
	)
)
